(kicad_pcb
	(version 20260206)
	(generator "pcbnew")
	(generator_version "10.0")
	(general
		(thickness 1.6)
		(legacy_teardrops no)
	)
	(paper "A4")
	(title_block
		(title "03242023_DA0F0TMBIJ0_F0T_Motherboard_J_brd_V01_OCP.brd")
		(comment 1 "Grand Teton / footprints 423-427 of 6105")
	)
	(layers
		(0 "F.Cu" signal "TOP")
		(4 "In1.Cu" signal "GND")
		(6 "In2.Cu" signal "IN1")
		(8 "In3.Cu" signal "GND1")
		(10 "In4.Cu" signal "IN2")
		(12 "In5.Cu" signal "GND2")
		(14 "In6.Cu" signal "IN3")
		(16 "In7.Cu" signal "GND3")
		(18 "In8.Cu" signal "VCC")
		(20 "In9.Cu" signal "VCC1")
		(22 "In10.Cu" signal "GND4")
		(24 "In11.Cu" signal "IN4")
		(26 "In12.Cu" signal "GND5")
		(28 "In13.Cu" signal "IN5")
		(30 "In14.Cu" signal "GND6")
		(32 "In15.Cu" signal "IN6")
		(34 "In16.Cu" signal "GND7")
		(2 "B.Cu" signal "BOTTOM")
		(9 "F.Adhes" user "F.Adhesive")
		(11 "B.Adhes" user "B.Adhesive")
		(13 "F.Paste" user "Package Geometry/Pastemask Top")
		(15 "B.Paste" user "Package Geometry/Pastemask Bottom")
		(5 "F.SilkS" user "Ref Des/Silkscreen Top")
		(7 "B.SilkS" user "Ref Des/Silkscreen Bottom")
		(1 "F.Mask" user "Board Geometry/Soldermask Top")
		(3 "B.Mask" user "Board Geometry/Soldermask Bottom")
		(17 "Dwgs.User" user "User.Drawings")
		(19 "Cmts.User" user "User.Comments")
		(21 "Eco1.User" user "User.Eco1")
		(23 "Eco2.User" user "User.Eco2")
		(25 "Edge.Cuts" user "Board Geometry/Outline")
		(27 "Margin" user)
		(31 "F.CrtYd" user "Package Geometry/Place Bound Top")
		(29 "B.CrtYd" user "Package Geometry/Place Bound Bottom")
		(35 "F.Fab" user "Ref Des/Assembly Top")
		(33 "B.Fab" user "Ref Des/Assembly Bottom")
	)
	(footprint ""
		(layer "F.Cu")
		(at 238.187738 -119.183658 -90)
		(property "Reference" "R3197"
			(at 0 0 270)
			(layer "F.SilkS")
			(hide yes)
			(effects
				(font
					(size 1.27 1.27)
				)
			)
		)
		(property "Value" ""
			(at 0 0 270)
			(layer "F.Fab")
			(effects
				(font
					(size 1.27 1.27)
				)
			)
		)
		(duplicate_pad_numbers_are_jumpers no)
		(fp_line
			(start 0.438658 0.4064)
			(end -0.287782 0.4064)
			(stroke
				(width 0.1524)
				(type default)
			)
			(layer "F.SilkS")
		)
		(fp_line
			(start -0.7874 0.121158)
			(end -0.7874 -0.4064)
			(stroke
				(width 0.1524)
				(type default)
			)
			(layer "F.SilkS")
		)
		(fp_line
			(start -0.7874 -0.4064)
			(end 0.7874 -0.4064)
			(stroke
				(width 0.1524)
				(type default)
			)
			(layer "F.SilkS")
		)
		(fp_line
			(start 0.7874 -0.4064)
			(end 0.7874 0.055118)
			(stroke
				(width 0.1524)
				(type default)
			)
			(layer "F.SilkS")
		)
		(fp_line
			(start -0.67945 0.3048)
			(end -0.67945 -0.305054)
			(stroke
				(width 0.1)
				(type default)
			)
			(layer "F.Fab")
		)
		(fp_line
			(start -0.12065 0.3048)
			(end -0.67945 0.3048)
			(stroke
				(width 0.1)
				(type default)
			)
			(layer "F.Fab")
		)
		(fp_line
			(start 0.120396 0.3048)
			(end 0.120396 0.2794)
			(stroke
				(width 0.1)
				(type default)
			)
			(layer "F.Fab")
		)
		(fp_line
			(start 0.67945 0.3048)
			(end 0.120396 0.3048)
			(stroke
				(width 0.1)
				(type default)
			)
			(layer "F.Fab")
		)
		(fp_line
			(start -0.12065 0.2794)
			(end -0.12065 0.3048)
			(stroke
				(width 0.1)
				(type default)
			)
			(layer "F.Fab")
		)
		(fp_line
			(start 0.120396 0.2794)
			(end -0.12065 0.2794)
			(stroke
				(width 0.1)
				(type default)
			)
			(layer "F.Fab")
		)
		(fp_line
			(start -0.12065 -0.2794)
			(end 0.12065 -0.2794)
			(stroke
				(width 0.1)
				(type default)
			)
			(layer "F.Fab")
		)
		(fp_line
			(start 0.12065 -0.2794)
			(end 0.12065 -0.3048)
			(stroke
				(width 0.1)
				(type default)
			)
			(layer "F.Fab")
		)
		(fp_line
			(start 0.12065 -0.3048)
			(end 0.67945 -0.3048)
			(stroke
				(width 0.1)
				(type default)
			)
			(layer "F.Fab")
		)
		(fp_line
			(start 0.67945 -0.3048)
			(end 0.67945 0.3048)
			(stroke
				(width 0.1)
				(type default)
			)
			(layer "F.Fab")
		)
		(fp_line
			(start -0.67945 -0.305054)
			(end -0.12065 -0.305054)
			(stroke
				(width 0.1)
				(type default)
			)
			(layer "F.Fab")
		)
		(fp_line
			(start -0.12065 -0.305054)
			(end -0.12065 -0.2794)
			(stroke
				(width 0.1)
				(type default)
			)
			(layer "F.Fab")
		)
		(pad "1" smd circle
			(at -0.40005 0 270)
			(size 0 0)
			(layers "F.Cu" "F.Mask" "F.Paste")
			(net "CLK_100M_OCP_V3_2_B_R_DN")
		)
		(pad "2" smd circle
			(at 0.40005 0 270)
			(size 0 0)
			(layers "F.Cu" "F.Mask" "F.Paste")
			(net "CLK_100M_OCP_V3_2_B_DN")
		)
	)
	(footprint ""
		(layer "F.Cu")
		(at 150.68296 -22.73808 90)
		(property "Reference" "R4720"
			(at 0 0 90)
			(layer "F.SilkS")
			(hide yes)
			(effects
				(font
					(size 1.27 1.27)
				)
			)
		)
		(property "Value" ""
			(at 0 0 90)
			(layer "F.Fab")
			(effects
				(font
					(size 1.27 1.27)
				)
			)
		)
		(duplicate_pad_numbers_are_jumpers no)
		(fp_line
			(start 0.7874 -0.4064)
			(end 0.7874 0.4064)
			(stroke
				(width 0.1524)
				(type default)
			)
			(layer "F.SilkS")
		)
		(fp_line
			(start -0.7874 -0.4064)
			(end 0.7874 -0.4064)
			(stroke
				(width 0.1524)
				(type default)
			)
			(layer "F.SilkS")
		)
		(fp_line
			(start 0.7874 0.4064)
			(end -0.7874 0.4064)
			(stroke
				(width 0.1524)
				(type default)
			)
			(layer "F.SilkS")
		)
		(fp_line
			(start -0.7874 0.4064)
			(end -0.7874 -0.4064)
			(stroke
				(width 0.1524)
				(type default)
			)
			(layer "F.SilkS")
		)
		(fp_line
			(start -0.12065 -0.305054)
			(end -0.12065 -0.2794)
			(stroke
				(width 0.1)
				(type default)
			)
			(layer "F.Fab")
		)
		(fp_line
			(start -0.67945 -0.305054)
			(end -0.12065 -0.305054)
			(stroke
				(width 0.1)
				(type default)
			)
			(layer "F.Fab")
		)
		(fp_line
			(start 0.67945 -0.3048)
			(end 0.67945 0.3048)
			(stroke
				(width 0.1)
				(type default)
			)
			(layer "F.Fab")
		)
		(fp_line
			(start 0.12065 -0.3048)
			(end 0.67945 -0.3048)
			(stroke
				(width 0.1)
				(type default)
			)
			(layer "F.Fab")
		)
		(fp_line
			(start 0.12065 -0.2794)
			(end 0.12065 -0.3048)
			(stroke
				(width 0.1)
				(type default)
			)
			(layer "F.Fab")
		)
		(fp_line
			(start -0.12065 -0.2794)
			(end 0.12065 -0.2794)
			(stroke
				(width 0.1)
				(type default)
			)
			(layer "F.Fab")
		)
		(fp_line
			(start 0.120396 0.2794)
			(end -0.12065 0.2794)
			(stroke
				(width 0.1)
				(type default)
			)
			(layer "F.Fab")
		)
		(fp_line
			(start -0.12065 0.2794)
			(end -0.12065 0.3048)
			(stroke
				(width 0.1)
				(type default)
			)
			(layer "F.Fab")
		)
		(fp_line
			(start 0.67945 0.3048)
			(end 0.120396 0.3048)
			(stroke
				(width 0.1)
				(type default)
			)
			(layer "F.Fab")
		)
		(fp_line
			(start 0.120396 0.3048)
			(end 0.120396 0.2794)
			(stroke
				(width 0.1)
				(type default)
			)
			(layer "F.Fab")
		)
		(fp_line
			(start -0.12065 0.3048)
			(end -0.67945 0.3048)
			(stroke
				(width 0.1)
				(type default)
			)
			(layer "F.Fab")
		)
		(fp_line
			(start -0.67945 0.3048)
			(end -0.67945 -0.305054)
			(stroke
				(width 0.1)
				(type default)
			)
			(layer "F.Fab")
		)
		(pad "1" smd circle
			(at -0.40005 0 90)
			(size 0 0)
			(layers "F.Cu" "F.Mask" "F.Paste")
			(net "FM_AC_PWR_BTN_N")
		)
		(pad "2" smd circle
			(at 0.40005 0 90)
			(size 0 0)
			(layers "F.Cu" "F.Mask" "F.Paste")
			(net "FM_AC_PWR_BTN_R_N")
		)
	)
	(footprint ""
		(layer "F.Cu")
		(at 182.14594 2.921)
		(property "Reference" "J79"
			(at -4.31927 1.016 90)
			(unlocked yes)
			(layer "F.SilkS")
			(effects
				(font
					(size 0.7874 0.5842)
					(thickness 0.1524)
				)
				(justify left)
			)
		)
		(property "Value" ""
			(at 0 0 0)
			(layer "F.Fab")
			(effects
				(font
					(size 1.27 1.27)
				)
			)
		)
		(duplicate_pad_numbers_are_jumpers no)
		(fp_line
			(start -1.2192 -2.1082)
			(end 1.2192 -2.1082)
			(stroke
				(width 0.1524)
				(type default)
			)
			(layer "F.SilkS")
		)
		(fp_line
			(start -1.2192 2.1082)
			(end -1.2192 -2.1082)
			(stroke
				(width 0.1524)
				(type default)
			)
			(layer "F.SilkS")
		)
		(fp_line
			(start 1.2192 -2.1082)
			(end 1.2192 2.1082)
			(stroke
				(width 0.1524)
				(type default)
			)
			(layer "F.SilkS")
		)
		(fp_line
			(start 1.2192 2.1082)
			(end -1.2192 2.1082)
			(stroke
				(width 0.1524)
				(type default)
			)
			(layer "F.SilkS")
		)
		(pad "" np_thru_hole circle
			(at -2.8829 -1.27 270)
			(size 1.0414 1.0414)
			(drill 1.0414)
			(layers "*.Cu" "*.Mask")
			(clearance 0.381)
			(thermal_gap 0.381)
		)
		(pad "" np_thru_hole circle
			(at -2.8829 1.27 270)
			(size 1.0414 1.0414)
			(drill 1.0414)
			(layers "*.Cu" "*.Mask")
			(clearance 0.381)
			(thermal_gap 0.381)
		)
		(pad "" np_thru_hole circle
			(at 3.4671 -1.27 270)
			(size 1.0414 1.0414)
			(drill 1.0414)
			(layers "*.Cu" "*.Mask")
			(clearance 0.381)
			(thermal_gap 0.381)
		)
		(pad "" np_thru_hole circle
			(at 3.4671 1.27 270)
			(size 1.0414 1.0414)
			(drill 1.0414)
			(layers "*.Cu" "*.Mask")
			(clearance 0.381)
			(thermal_gap 0.381)
		)
		(pad "1" smd rect
			(at 0.8255 -0.249936 270)
			(size 0.3048 0.508)
			(layers "F.Cu" "F.Mask" "F.Paste")
			(net "DELTA_L_85_10INCH_IN3_DP")
		)
		(pad "2" smd rect
			(at 0.8255 0.249936 270)
			(size 0.3048 0.508)
			(layers "F.Cu" "F.Mask" "F.Paste")
			(net "DELTA_L_85_10INCH_IN3_DN")
		)
		(pad "3" smd circle
			(at 0 0)
			(size 0 0)
			(layers "F.Cu" "F.Mask" "F.Paste")
			(net "DELTA_L_GND_1")
		)
		(zone
			(layer "F.Cu")
			(hatch none 0.5)
			(connect_pads
				(clearance 0)
			)
			(min_thickness 0.25)
			(keepout
				(tracks not_allowed)
				(vias allowed)
				(pads allowed)
				(copperpour not_allowed)
				(footprints allowed)
			)
			(placement
				(enabled no)
				(sheetname "")
			)
			(fill
				(thermal_gap 0.5)
				(thermal_bridge_width 0.5)
				(island_removal_mode 0)
			)
			(polygon
				(pts
					(xy 183.26354 2.37236) (xy 183.26354 2.467864) (xy 182.66664 2.467864) (xy 182.66664 2.874264)
					(xy 183.26354 2.874264) (xy 183.26354 2.967736) (xy 182.66664 2.967736) (xy 182.66664 3.374136)
					(xy 183.26354 3.374136) (xy 183.26354 3.46964) (xy 182.56504 3.46964) (xy 182.56504 2.37236)
				)
			)
		)
		(zone
			(layers "F.Cu" "B.Cu" "In1.Cu" "In2.Cu" "In3.Cu" "In4.Cu" "In5.Cu" "In6.Cu"
				"In7.Cu" "In8.Cu" "In9.Cu" "In10.Cu" "In11.Cu" "In12.Cu" "In13.Cu" "In14.Cu"
				"In15.Cu" "In16.Cu"
			)
			(hatch none 0.5)
			(connect_pads
				(clearance 0)
			)
			(min_thickness 0.25)
			(keepout
				(tracks not_allowed)
				(vias allowed)
				(pads allowed)
				(copperpour not_allowed)
				(footprints allowed)
			)
			(placement
				(enabled no)
				(sheetname "")
			)
			(fill
				(thermal_gap 0.5)
				(thermal_bridge_width 0.5)
				(island_removal_mode 0)
			)
			(polygon
				(pts
					(arc
						(start 180.19014 1.651)
						(mid 178.33594 1.651)
						(end 180.19014 1.651)
					)
				)
			)
		)
		(zone
			(layers "F.Cu" "B.Cu" "In1.Cu" "In2.Cu" "In3.Cu" "In4.Cu" "In5.Cu" "In6.Cu"
				"In7.Cu" "In8.Cu" "In9.Cu" "In10.Cu" "In11.Cu" "In12.Cu" "In13.Cu" "In14.Cu"
				"In15.Cu" "In16.Cu"
			)
			(hatch none 0.5)
			(connect_pads
				(clearance 0)
			)
			(min_thickness 0.25)
			(keepout
				(tracks not_allowed)
				(vias allowed)
				(pads allowed)
				(copperpour not_allowed)
				(footprints allowed)
			)
			(placement
				(enabled no)
				(sheetname "")
			)
			(fill
				(thermal_gap 0.5)
				(thermal_bridge_width 0.5)
				(island_removal_mode 0)
			)
			(polygon
				(pts
					(arc
						(start 180.19014 4.191)
						(mid 178.33594 4.191)
						(end 180.19014 4.191)
					)
				)
			)
		)
		(zone
			(layers "F.Cu" "B.Cu" "In1.Cu" "In2.Cu" "In3.Cu" "In4.Cu" "In5.Cu" "In6.Cu"
				"In7.Cu" "In8.Cu" "In9.Cu" "In10.Cu" "In11.Cu" "In12.Cu" "In13.Cu" "In14.Cu"
				"In15.Cu" "In16.Cu"
			)
			(hatch none 0.5)
			(connect_pads
				(clearance 0)
			)
			(min_thickness 0.25)
			(keepout
				(tracks not_allowed)
				(vias allowed)
				(pads allowed)
				(copperpour not_allowed)
				(footprints allowed)
			)
			(placement
				(enabled no)
				(sheetname "")
			)
			(fill
				(thermal_gap 0.5)
				(thermal_bridge_width 0.5)
				(island_removal_mode 0)
			)
			(polygon
				(pts
					(arc
						(start 186.54014 1.651)
						(mid 184.68594 1.651)
						(end 186.54014 1.651)
					)
				)
			)
		)
		(zone
			(layers "F.Cu" "B.Cu" "In1.Cu" "In2.Cu" "In3.Cu" "In4.Cu" "In5.Cu" "In6.Cu"
				"In7.Cu" "In8.Cu" "In9.Cu" "In10.Cu" "In11.Cu" "In12.Cu" "In13.Cu" "In14.Cu"
				"In15.Cu" "In16.Cu"
			)
			(hatch none 0.5)
			(connect_pads
				(clearance 0)
			)
			(min_thickness 0.25)
			(keepout
				(tracks not_allowed)
				(vias allowed)
				(pads allowed)
				(copperpour not_allowed)
				(footprints allowed)
			)
			(placement
				(enabled no)
				(sheetname "")
			)
			(fill
				(thermal_gap 0.5)
				(thermal_bridge_width 0.5)
				(island_removal_mode 0)
			)
			(polygon
				(pts
					(arc
						(start 186.54014 4.191)
						(mid 184.68594 4.191)
						(end 186.54014 4.191)
					)
				)
			)
		)
	)
	(footprint ""
		(layer "F.Cu")
		(at 248.740676 -90.65514)
		(property "Reference" "C2036"
			(at 0 0 0)
			(layer "F.SilkS")
			(hide yes)
			(effects
				(font
					(size 1.27 1.27)
				)
			)
		)
		(property "Value" ""
			(at 0 0 0)
			(layer "F.Fab")
			(effects
				(font
					(size 1.27 1.27)
				)
			)
		)
		(duplicate_pad_numbers_are_jumpers no)
		(fp_line
			(start -0.7874 -0.4064)
			(end 0.7874 -0.4064)
			(stroke
				(width 0.1524)
				(type default)
			)
			(layer "F.SilkS")
		)
		(fp_line
			(start -0.7874 0.4064)
			(end -0.7874 -0.4064)
			(stroke
				(width 0.1524)
				(type default)
			)
			(layer "F.SilkS")
		)
		(fp_line
			(start 0.7874 -0.4064)
			(end 0.7874 0.4064)
			(stroke
				(width 0.1524)
				(type default)
			)
			(layer "F.SilkS")
		)
		(fp_line
			(start 0.7874 0.4064)
			(end -0.7874 0.4064)
			(stroke
				(width 0.1524)
				(type default)
			)
			(layer "F.SilkS")
		)
		(fp_line
			(start -0.67945 -0.305054)
			(end -0.12065 -0.305054)
			(stroke
				(width 0.1)
				(type default)
			)
			(layer "F.Fab")
		)
		(fp_line
			(start -0.67945 0.3048)
			(end -0.67945 -0.305054)
			(stroke
				(width 0.1)
				(type default)
			)
			(layer "F.Fab")
		)
		(fp_line
			(start -0.12065 -0.305054)
			(end -0.12065 -0.2794)
			(stroke
				(width 0.1)
				(type default)
			)
			(layer "F.Fab")
		)
		(fp_line
			(start -0.12065 -0.2794)
			(end 0.12065 -0.2794)
			(stroke
				(width 0.1)
				(type default)
			)
			(layer "F.Fab")
		)
		(fp_line
			(start -0.12065 0.2794)
			(end -0.12065 0.3048)
			(stroke
				(width 0.1)
				(type default)
			)
			(layer "F.Fab")
		)
		(fp_line
			(start -0.12065 0.3048)
			(end -0.67945 0.3048)
			(stroke
				(width 0.1)
				(type default)
			)
			(layer "F.Fab")
		)
		(fp_line
			(start 0.120396 0.2794)
			(end -0.12065 0.2794)
			(stroke
				(width 0.1)
				(type default)
			)
			(layer "F.Fab")
		)
		(fp_line
			(start 0.120396 0.3048)
			(end 0.120396 0.2794)
			(stroke
				(width 0.1)
				(type default)
			)
			(layer "F.Fab")
		)
		(fp_line
			(start 0.12065 -0.3048)
			(end 0.67945 -0.3048)
			(stroke
				(width 0.1)
				(type default)
			)
			(layer "F.Fab")
		)
		(fp_line
			(start 0.12065 -0.2794)
			(end 0.12065 -0.3048)
			(stroke
				(width 0.1)
				(type default)
			)
			(layer "F.Fab")
		)
		(fp_line
			(start 0.67945 -0.3048)
			(end 0.67945 0.3048)
			(stroke
				(width 0.1)
				(type default)
			)
			(layer "F.Fab")
		)
		(fp_line
			(start 0.67945 0.3048)
			(end 0.120396 0.3048)
			(stroke
				(width 0.1)
				(type default)
			)
			(layer "F.Fab")
		)
		(pad "1" smd circle
			(at -0.40005 0)
			(size 0 0)
			(layers "F.Cu" "F.Mask" "F.Paste")
			(net "XTAL_CLK_GEN1_25M_X1_R")
		)
		(pad "2" smd circle
			(at 0.40005 0)
			(size 0 0)
			(layers "F.Cu" "F.Mask" "F.Paste")
			(net "GND")
		)
	)
	(footprint ""
		(layer "F.Cu")
		(at 176.391062 -32.935672 90)
		(property "Reference" "PC2232"
			(at 0 0 90)
			(layer "F.SilkS")
			(hide yes)
			(effects
				(font
					(size 1.27 1.27)
				)
			)
		)
		(property "Value" ""
			(at 0 0 90)
			(layer "F.Fab")
			(effects
				(font
					(size 1.27 1.27)
				)
			)
		)
		(duplicate_pad_numbers_are_jumpers no)
		(fp_line
			(start 0.7874 -0.4064)
			(end 0.7874 0.4064)
			(stroke
				(width 0.1524)
				(type default)
			)
			(layer "F.SilkS")
		)
		(fp_line
			(start -0.7874 -0.4064)
			(end 0.7874 -0.4064)
			(stroke
				(width 0.1524)
				(type default)
			)
			(layer "F.SilkS")
		)
		(fp_line
			(start 0.7874 0.4064)
			(end -0.7874 0.4064)
			(stroke
				(width 0.1524)
				(type default)
			)
			(layer "F.SilkS")
		)
		(fp_line
			(start -0.7874 0.4064)
			(end -0.7874 -0.4064)
			(stroke
				(width 0.1524)
				(type default)
			)
			(layer "F.SilkS")
		)
		(fp_line
			(start -0.12065 -0.305054)
			(end -0.12065 -0.2794)
			(stroke
				(width 0.1)
				(type default)
			)
			(layer "F.Fab")
		)
		(fp_line
			(start -0.67945 -0.305054)
			(end -0.12065 -0.305054)
			(stroke
				(width 0.1)
				(type default)
			)
			(layer "F.Fab")
		)
		(fp_line
			(start 0.67945 -0.3048)
			(end 0.67945 0.3048)
			(stroke
				(width 0.1)
				(type default)
			)
			(layer "F.Fab")
		)
		(fp_line
			(start 0.12065 -0.3048)
			(end 0.67945 -0.3048)
			(stroke
				(width 0.1)
				(type default)
			)
			(layer "F.Fab")
		)
		(fp_line
			(start 0.12065 -0.2794)
			(end 0.12065 -0.3048)
			(stroke
				(width 0.1)
				(type default)
			)
			(layer "F.Fab")
		)
		(fp_line
			(start -0.12065 -0.2794)
			(end 0.12065 -0.2794)
			(stroke
				(width 0.1)
				(type default)
			)
			(layer "F.Fab")
		)
		(fp_line
			(start 0.120396 0.2794)
			(end -0.12065 0.2794)
			(stroke
				(width 0.1)
				(type default)
			)
			(layer "F.Fab")
		)
		(fp_line
			(start -0.12065 0.2794)
			(end -0.12065 0.3048)
			(stroke
				(width 0.1)
				(type default)
			)
			(layer "F.Fab")
		)
		(fp_line
			(start 0.67945 0.3048)
			(end 0.120396 0.3048)
			(stroke
				(width 0.1)
				(type default)
			)
			(layer "F.Fab")
		)
		(fp_line
			(start 0.120396 0.3048)
			(end 0.120396 0.2794)
			(stroke
				(width 0.1)
				(type default)
			)
			(layer "F.Fab")
		)
		(fp_line
			(start -0.12065 0.3048)
			(end -0.67945 0.3048)
			(stroke
				(width 0.1)
				(type default)
			)
			(layer "F.Fab")
		)
		(fp_line
			(start -0.67945 0.3048)
			(end -0.67945 -0.305054)
			(stroke
				(width 0.1)
				(type default)
			)
			(layer "F.Fab")
		)
		(pad "1" smd circle
			(at -0.40005 0 90)
			(size 0 0)
			(layers "F.Cu" "F.Mask" "F.Paste")
			(net "P12V_SCM_SS")
		)
		(pad "2" smd circle
			(at 0.40005 0 90)
			(size 0 0)
			(layers "F.Cu" "F.Mask" "F.Paste")
			(net "GND")
		)
	)
)
